# S9S_MB_2U (Grand Teton) — schematic netlist excerpt (pin names and nets, part order shuffled) for the footprints in the layout excerpt that follows; sources: Cadence DE-HDL packaged netlist, KiCad conversion of 03242023_DA0F0TMBIJ0_F0T_Motherboard_J_brd_V01_OCP.brd

C2372  Q_CAP  1000PF 50V 5% EMPTY  pkg 0402  page 144 : A = PRSNT_SWB_ISO_N ; B = GND
C280  Q_CAP  22UF 4V 20% X6S  pkg C0402  page 77 : A = PVCCIN_CPU1 ; B = GND
C734  Q_CAP_DIFFBUS  DIFF BUS_0.22UF 6.3V 20% X6S  pkg C0201  page 176 : \1\ = P5E_CPU1_PE0_TX_C_DN<3> ; \2\ = P5E_CPU1_PE0_TX_DN<3>

(kicad_pcb
	(version 20260206)
	(generator "pcbnew")
	(generator_version "10.0")
	(general
		(thickness 1.6)
		(legacy_teardrops no)
	)
	(paper "A4")
	(title_block
		(title "03242023_DA0F0TMBIJ0_F0T_Motherboard_J_brd_V01_OCP.brd")
		(comment 1 "Grand Teton / footprints 199-201 of 6105")
	)
	(layers
		(0 "F.Cu" signal "TOP")
		(4 "In1.Cu" signal "GND")
		(6 "In2.Cu" signal "IN1")
		(8 "In3.Cu" signal "GND1")
		(10 "In4.Cu" signal "IN2")
		(12 "In5.Cu" signal "GND2")
		(14 "In6.Cu" signal "IN3")
		(16 "In7.Cu" signal "GND3")
		(18 "In8.Cu" signal "VCC")
		(20 "In9.Cu" signal "VCC1")
		(22 "In10.Cu" signal "GND4")
		(24 "In11.Cu" signal "IN4")
		(26 "In12.Cu" signal "GND5")
		(28 "In13.Cu" signal "IN5")
		(30 "In14.Cu" signal "GND6")
		(32 "In15.Cu" signal "IN6")
		(34 "In16.Cu" signal "GND7")
		(2 "B.Cu" signal "BOTTOM")
		(9 "F.Adhes" user "F.Adhesive")
		(11 "B.Adhes" user "B.Adhesive")
		(13 "F.Paste" user "Package Geometry/Pastemask Top")
		(15 "B.Paste" user "Package Geometry/Pastemask Bottom")
		(5 "F.SilkS" user "Ref Des/Silkscreen Top")
		(7 "B.SilkS" user "Ref Des/Silkscreen Bottom")
		(1 "F.Mask" user "Board Geometry/Soldermask Top")
		(3 "B.Mask" user "Board Geometry/Soldermask Bottom")
		(17 "Dwgs.User" user "User.Drawings")
		(19 "Cmts.User" user "User.Comments")
		(21 "Eco1.User" user "User.Eco1")
		(23 "Eco2.User" user "User.Eco2")
		(25 "Edge.Cuts" user "Board Geometry/Outline")
		(27 "Margin" user)
		(31 "F.CrtYd" user "Package Geometry/Place Bound Top")
		(29 "B.CrtYd" user "Package Geometry/Place Bound Bottom")
		(35 "F.Fab" user "Ref Des/Assembly Top")
		(33 "B.Fab" user "Ref Des/Assembly Bottom")
	)
	(footprint ""
		(layer "F.Cu")
		(at 104.8258 -407.289 180)
		(property "Reference" "C2372"
			(at 0 0 180)
			(layer "F.SilkS")
			(hide yes)
			(effects
				(font
					(size 1.27 1.27)
				)
			)
		)
		(property "Value" ""
			(at 0 0 180)
			(layer "F.Fab")
			(effects
				(font
					(size 1.27 1.27)
				)
			)
		)
		(duplicate_pad_numbers_are_jumpers no)
		(fp_line
			(start 0.7874 0.4064)
			(end -0.7874 0.4064)
			(stroke
				(width 0.1524)
				(type default)
			)
			(layer "F.SilkS")
		)
		(fp_line
			(start 0.7874 -0.4064)
			(end 0.7874 0.4064)
			(stroke
				(width 0.1524)
				(type default)
			)
			(layer "F.SilkS")
		)
		(fp_line
			(start -0.7874 0.4064)
			(end -0.7874 -0.4064)
			(stroke
				(width 0.1524)
				(type default)
			)
			(layer "F.SilkS")
		)
		(fp_line
			(start -0.7874 -0.4064)
			(end 0.7874 -0.4064)
			(stroke
				(width 0.1524)
				(type default)
			)
			(layer "F.SilkS")
		)
		(fp_line
			(start 0.67945 0.3048)
			(end 0.120396 0.3048)
			(stroke
				(width 0.1)
				(type default)
			)
			(layer "F.Fab")
		)
		(fp_line
			(start 0.67945 -0.3048)
			(end 0.67945 0.3048)
			(stroke
				(width 0.1)
				(type default)
			)
			(layer "F.Fab")
		)
		(fp_line
			(start 0.12065 -0.2794)
			(end 0.12065 -0.3048)
			(stroke
				(width 0.1)
				(type default)
			)
			(layer "F.Fab")
		)
		(fp_line
			(start 0.12065 -0.3048)
			(end 0.67945 -0.3048)
			(stroke
				(width 0.1)
				(type default)
			)
			(layer "F.Fab")
		)
		(fp_line
			(start 0.120396 0.3048)
			(end 0.120396 0.2794)
			(stroke
				(width 0.1)
				(type default)
			)
			(layer "F.Fab")
		)
		(fp_line
			(start 0.120396 0.2794)
			(end -0.12065 0.2794)
			(stroke
				(width 0.1)
				(type default)
			)
			(layer "F.Fab")
		)
		(fp_line
			(start -0.12065 0.3048)
			(end -0.67945 0.3048)
			(stroke
				(width 0.1)
				(type default)
			)
			(layer "F.Fab")
		)
		(fp_line
			(start -0.12065 0.2794)
			(end -0.12065 0.3048)
			(stroke
				(width 0.1)
				(type default)
			)
			(layer "F.Fab")
		)
		(fp_line
			(start -0.12065 -0.2794)
			(end 0.12065 -0.2794)
			(stroke
				(width 0.1)
				(type default)
			)
			(layer "F.Fab")
		)
		(fp_line
			(start -0.12065 -0.305054)
			(end -0.12065 -0.2794)
			(stroke
				(width 0.1)
				(type default)
			)
			(layer "F.Fab")
		)
		(fp_line
			(start -0.67945 0.3048)
			(end -0.67945 -0.305054)
			(stroke
				(width 0.1)
				(type default)
			)
			(layer "F.Fab")
		)
		(fp_line
			(start -0.67945 -0.305054)
			(end -0.12065 -0.305054)
			(stroke
				(width 0.1)
				(type default)
			)
			(layer "F.Fab")
		)
		(pad "1" smd circle
			(at -0.40005 0 180)
			(size 0 0)
			(layers "F.Cu" "F.Mask" "F.Paste")
			(net "PRSNT_SWB_ISO_N")
		)
		(pad "2" smd circle
			(at 0.40005 0 180)
			(size 0 0)
			(layers "F.Cu" "F.Mask" "F.Paste")
			(net "GND")
		)
	)
	(footprint ""
		(layer "F.Cu")
		(at 106.32313 -241.97691 -90)
		(property "Reference" "C280"
			(at 0 0 270)
			(layer "F.SilkS")
			(hide yes)
			(effects
				(font
					(size 1.27 1.27)
				)
			)
		)
		(property "Value" ""
			(at 0 0 270)
			(layer "F.Fab")
			(effects
				(font
					(size 1.27 1.27)
				)
			)
		)
		(duplicate_pad_numbers_are_jumpers no)
		(fp_line
			(start -0.7874 0.4064)
			(end -0.7874 -0.4064)
			(stroke
				(width 0.1524)
				(type default)
			)
			(layer "F.SilkS")
		)
		(fp_line
			(start 0.7874 0.4064)
			(end -0.7874 0.4064)
			(stroke
				(width 0.1524)
				(type default)
			)
			(layer "F.SilkS")
		)
		(fp_line
			(start -0.7874 -0.4064)
			(end 0.7874 -0.4064)
			(stroke
				(width 0.1524)
				(type default)
			)
			(layer "F.SilkS")
		)
		(fp_line
			(start 0.7874 -0.4064)
			(end 0.7874 0.4064)
			(stroke
				(width 0.1524)
				(type default)
			)
			(layer "F.SilkS")
		)
		(fp_line
			(start -0.67945 0.3048)
			(end -0.67945 -0.305054)
			(stroke
				(width 0.1)
				(type default)
			)
			(layer "F.Fab")
		)
		(fp_line
			(start -0.12065 0.3048)
			(end -0.67945 0.3048)
			(stroke
				(width 0.1)
				(type default)
			)
			(layer "F.Fab")
		)
		(fp_line
			(start 0.120396 0.3048)
			(end 0.120396 0.2794)
			(stroke
				(width 0.1)
				(type default)
			)
			(layer "F.Fab")
		)
		(fp_line
			(start 0.67945 0.3048)
			(end 0.120396 0.3048)
			(stroke
				(width 0.1)
				(type default)
			)
			(layer "F.Fab")
		)
		(fp_line
			(start -0.12065 0.2794)
			(end -0.12065 0.3048)
			(stroke
				(width 0.1)
				(type default)
			)
			(layer "F.Fab")
		)
		(fp_line
			(start 0.120396 0.2794)
			(end -0.12065 0.2794)
			(stroke
				(width 0.1)
				(type default)
			)
			(layer "F.Fab")
		)
		(fp_line
			(start -0.12065 -0.2794)
			(end 0.12065 -0.2794)
			(stroke
				(width 0.1)
				(type default)
			)
			(layer "F.Fab")
		)
		(fp_line
			(start 0.12065 -0.2794)
			(end 0.12065 -0.3048)
			(stroke
				(width 0.1)
				(type default)
			)
			(layer "F.Fab")
		)
		(fp_line
			(start 0.12065 -0.3048)
			(end 0.67945 -0.3048)
			(stroke
				(width 0.1)
				(type default)
			)
			(layer "F.Fab")
		)
		(fp_line
			(start 0.67945 -0.3048)
			(end 0.67945 0.3048)
			(stroke
				(width 0.1)
				(type default)
			)
			(layer "F.Fab")
		)
		(fp_line
			(start -0.67945 -0.305054)
			(end -0.12065 -0.305054)
			(stroke
				(width 0.1)
				(type default)
			)
			(layer "F.Fab")
		)
		(fp_line
			(start -0.12065 -0.305054)
			(end -0.12065 -0.2794)
			(stroke
				(width 0.1)
				(type default)
			)
			(layer "F.Fab")
		)
		(pad "1" smd circle
			(at -0.40005 0 270)
			(size 0 0)
			(layers "F.Cu" "F.Mask" "F.Paste")
			(net "PVCCIN_CPU1")
		)
		(pad "2" smd circle
			(at 0.40005 0 270)
			(size 0 0)
			(layers "F.Cu" "F.Mask" "F.Paste")
			(net "GND")
		)
	)
	(footprint ""
		(layer "F.Cu")
		(at 84.713318 -402.371052 -90)
		(property "Reference" "C734"
			(at 0 0 270)
			(layer "F.SilkS")
			(hide yes)
			(effects
				(font
					(size 1.27 1.27)
				)
			)
		)
		(property "Value" ""
			(at 0 0 270)
			(layer "F.Fab")
			(effects
				(font
					(size 1.27 1.27)
				)
			)
		)
		(duplicate_pad_numbers_are_jumpers no)
		(fp_line
			(start -0.299974 0.150114)
			(end -0.299974 -0.150114)
			(stroke
				(width 0.1)
				(type default)
			)
			(layer "F.Fab")
		)
		(fp_line
			(start 0.299974 0.150114)
			(end -0.299974 0.150114)
			(stroke
				(width 0.1)
				(type default)
			)
			(layer "F.Fab")
		)
		(fp_line
			(start -0.299974 -0.150114)
			(end 0.299974 -0.150114)
			(stroke
				(width 0.1)
				(type default)
			)
			(layer "F.Fab")
		)
		(fp_line
			(start 0.299974 -0.150114)
			(end 0.299974 0.150114)
			(stroke
				(width 0.1)
				(type default)
			)
			(layer "F.Fab")
		)
		(pad "1" smd rect
			(at -0.2667 0 270)
			(size 0.3048 0.381)
			(layers "F.Cu" "F.Mask" "F.Paste")
			(net "P5E_CPU1_PE0_TX_C_DN<3>")
		)
		(pad "2" smd rect
			(at 0.2667 0 270)
			(size 0.3048 0.381)
			(layers "F.Cu" "F.Mask" "F.Paste")
			(net "P5E_CPU1_PE0_TX_DN<3>")
		)
	)
)
